# S9S_MB_2U (Grand Teton) — schematic netlist excerpt (pin names and nets, part order shuffled) for the footprints in the layout excerpt that follows; sources: Cadence DE-HDL packaged netlist, KiCad conversion of 03242023_DA0F0TMBIJ0_F0T_Motherboard_J_brd_V01_OCP.brd

R259  Q_RES  240 1% CHIP  pkg 0402LF  page 120 : A = PVNN_TERM_CPU1 ; B = FM_S3M_CPU1_LVC1_GPIO_2
PR130  Q_RES  1 1% CHIP  pkg 0402LF  page 274 : A = PVCCINFAON_CPU0_VCC ; B = P3V3_AUX

(kicad_pcb
	(version 20260206)
	(generator "pcbnew")
	(generator_version "10.0")
	(general
		(thickness 1.6)
		(legacy_teardrops no)
	)
	(paper "A4")
	(title_block
		(title "03242023_DA0F0TMBIJ0_F0T_Motherboard_J_brd_V01_OCP.brd")
		(comment 1 "Grand Teton / footprints 5509-5510 of 6105")
	)
	(layers
		(0 "F.Cu" signal "TOP")
		(4 "In1.Cu" signal "GND")
		(6 "In2.Cu" signal "IN1")
		(8 "In3.Cu" signal "GND1")
		(10 "In4.Cu" signal "IN2")
		(12 "In5.Cu" signal "GND2")
		(14 "In6.Cu" signal "IN3")
		(16 "In7.Cu" signal "GND3")
		(18 "In8.Cu" signal "VCC")
		(20 "In9.Cu" signal "VCC1")
		(22 "In10.Cu" signal "GND4")
		(24 "In11.Cu" signal "IN4")
		(26 "In12.Cu" signal "GND5")
		(28 "In13.Cu" signal "IN5")
		(30 "In14.Cu" signal "GND6")
		(32 "In15.Cu" signal "IN6")
		(34 "In16.Cu" signal "GND7")
		(2 "B.Cu" signal "BOTTOM")
		(9 "F.Adhes" user "F.Adhesive")
		(11 "B.Adhes" user "B.Adhesive")
		(13 "F.Paste" user "Package Geometry/Pastemask Top")
		(15 "B.Paste" user "Package Geometry/Pastemask Bottom")
		(5 "F.SilkS" user "Ref Des/Silkscreen Top")
		(7 "B.SilkS" user "Ref Des/Silkscreen Bottom")
		(1 "F.Mask" user "Board Geometry/Soldermask Top")
		(3 "B.Mask" user "Board Geometry/Soldermask Bottom")
		(17 "Dwgs.User" user "User.Drawings")
		(19 "Cmts.User" user "User.Comments")
		(21 "Eco1.User" user "User.Eco1")
		(23 "Eco2.User" user "User.Eco2")
		(25 "Edge.Cuts" user "Board Geometry/Outline")
		(27 "Margin" user)
		(31 "F.CrtYd" user "Package Geometry/Place Bound Top")
		(29 "B.CrtYd" user "Package Geometry/Place Bound Bottom")
		(35 "F.Fab" user "Ref Des/Assembly Top")
		(33 "B.Fab" user "Ref Des/Assembly Bottom")
	)
	(footprint ""
		(layer "B.Cu")
		(at 420.698422 -132.632704)
		(property "Reference" "PR130"
			(at 0 0 0)
			(layer "B.SilkS")
			(hide yes)
			(effects
				(font
					(size 1.27 1.27)
				)
				(justify mirror)
			)
		)
		(property "Value" ""
			(at 0 0 0)
			(layer "B.Fab")
			(effects
				(font
					(size 1.27 1.27)
				)
				(justify mirror)
			)
		)
		(duplicate_pad_numbers_are_jumpers no)
		(fp_line
			(start -0.7874 -0.4064)
			(end -0.7874 0.4064)
			(stroke
				(width 0.1524)
				(type default)
			)
			(layer "B.SilkS")
		)
		(fp_line
			(start -0.7874 0.4064)
			(end 0.7874 0.4064)
			(stroke
				(width 0.1524)
				(type default)
			)
			(layer "B.SilkS")
		)
		(fp_line
			(start 0.7874 -0.4064)
			(end -0.7874 -0.4064)
			(stroke
				(width 0.1524)
				(type default)
			)
			(layer "B.SilkS")
		)
		(fp_line
			(start 0.7874 0.4064)
			(end 0.7874 -0.4064)
			(stroke
				(width 0.1524)
				(type default)
			)
			(layer "B.SilkS")
		)
		(fp_line
			(start -0.67945 -0.3048)
			(end -0.67945 0.3048)
			(stroke
				(width 0.1)
				(type default)
			)
			(layer "B.Fab")
		)
		(fp_line
			(start -0.67945 0.3048)
			(end -0.120396 0.3048)
			(stroke
				(width 0.1)
				(type default)
			)
			(layer "B.Fab")
		)
		(fp_line
			(start -0.12065 -0.3048)
			(end -0.67945 -0.3048)
			(stroke
				(width 0.1)
				(type default)
			)
			(layer "B.Fab")
		)
		(fp_line
			(start -0.12065 -0.2794)
			(end -0.12065 -0.3048)
			(stroke
				(width 0.1)
				(type default)
			)
			(layer "B.Fab")
		)
		(fp_line
			(start -0.120396 0.2794)
			(end 0.12065 0.2794)
			(stroke
				(width 0.1)
				(type default)
			)
			(layer "B.Fab")
		)
		(fp_line
			(start -0.120396 0.3048)
			(end -0.120396 0.2794)
			(stroke
				(width 0.1)
				(type default)
			)
			(layer "B.Fab")
		)
		(fp_line
			(start 0.12065 -0.305054)
			(end 0.12065 -0.2794)
			(stroke
				(width 0.1)
				(type default)
			)
			(layer "B.Fab")
		)
		(fp_line
			(start 0.12065 -0.2794)
			(end -0.12065 -0.2794)
			(stroke
				(width 0.1)
				(type default)
			)
			(layer "B.Fab")
		)
		(fp_line
			(start 0.12065 0.2794)
			(end 0.12065 0.3048)
			(stroke
				(width 0.1)
				(type default)
			)
			(layer "B.Fab")
		)
		(fp_line
			(start 0.12065 0.3048)
			(end 0.67945 0.3048)
			(stroke
				(width 0.1)
				(type default)
			)
			(layer "B.Fab")
		)
		(fp_line
			(start 0.67945 -0.305054)
			(end 0.12065 -0.305054)
			(stroke
				(width 0.1)
				(type default)
			)
			(layer "B.Fab")
		)
		(fp_line
			(start 0.67945 0.3048)
			(end 0.67945 -0.305054)
			(stroke
				(width 0.1)
				(type default)
			)
			(layer "B.Fab")
		)
		(pad "1" smd circle
			(at 0.40005 0 180)
			(size 0 0)
			(layers "B.Cu" "B.Mask" "B.Paste")
			(net "PVCCINFAON_CPU0_VCC")
		)
		(pad "2" smd circle
			(at -0.40005 0 180)
			(size 0 0)
			(layers "B.Cu" "B.Mask" "B.Paste")
			(net "P3V3_AUX")
		)
	)
	(footprint ""
		(layer "B.Cu")
		(at 49.682908 -193.25971 -90)
		(property "Reference" "R259"
			(at 0 0 90)
			(layer "B.SilkS")
			(hide yes)
			(effects
				(font
					(size 1.27 1.27)
				)
				(justify mirror)
			)
		)
		(property "Value" ""
			(at 0 0 90)
			(layer "B.Fab")
			(effects
				(font
					(size 1.27 1.27)
				)
				(justify mirror)
			)
		)
		(duplicate_pad_numbers_are_jumpers no)
		(fp_line
			(start -0.7874 0.4064)
			(end 0.7874 0.4064)
			(stroke
				(width 0.1524)
				(type default)
			)
			(layer "B.SilkS")
		)
		(fp_line
			(start 0.7874 0.4064)
			(end 0.7874 -0.4064)
			(stroke
				(width 0.1524)
				(type default)
			)
			(layer "B.SilkS")
		)
		(fp_line
			(start -0.7874 -0.4064)
			(end -0.7874 0.4064)
			(stroke
				(width 0.1524)
				(type default)
			)
			(layer "B.SilkS")
		)
		(fp_line
			(start 0.7874 -0.4064)
			(end -0.7874 -0.4064)
			(stroke
				(width 0.1524)
				(type default)
			)
			(layer "B.SilkS")
		)
		(fp_line
			(start -0.67945 0.3048)
			(end -0.120396 0.3048)
			(stroke
				(width 0.1)
				(type default)
			)
			(layer "B.Fab")
		)
		(fp_line
			(start -0.120396 0.3048)
			(end -0.120396 0.2794)
			(stroke
				(width 0.1)
				(type default)
			)
			(layer "B.Fab")
		)
		(fp_line
			(start 0.12065 0.3048)
			(end 0.67945 0.3048)
			(stroke
				(width 0.1)
				(type default)
			)
			(layer "B.Fab")
		)
		(fp_line
			(start 0.67945 0.3048)
			(end 0.67945 -0.305054)
			(stroke
				(width 0.1)
				(type default)
			)
			(layer "B.Fab")
		)
		(fp_line
			(start -0.120396 0.2794)
			(end 0.12065 0.2794)
			(stroke
				(width 0.1)
				(type default)
			)
			(layer "B.Fab")
		)
		(fp_line
			(start 0.12065 0.2794)
			(end 0.12065 0.3048)
			(stroke
				(width 0.1)
				(type default)
			)
			(layer "B.Fab")
		)
		(fp_line
			(start -0.12065 -0.2794)
			(end -0.12065 -0.3048)
			(stroke
				(width 0.1)
				(type default)
			)
			(layer "B.Fab")
		)
		(fp_line
			(start 0.12065 -0.2794)
			(end -0.12065 -0.2794)
			(stroke
				(width 0.1)
				(type default)
			)
			(layer "B.Fab")
		)
		(fp_line
			(start -0.67945 -0.3048)
			(end -0.67945 0.3048)
			(stroke
				(width 0.1)
				(type default)
			)
			(layer "B.Fab")
		)
		(fp_line
			(start -0.12065 -0.3048)
			(end -0.67945 -0.3048)
			(stroke
				(width 0.1)
				(type default)
			)
			(layer "B.Fab")
		)
		(fp_line
			(start 0.12065 -0.305054)
			(end 0.12065 -0.2794)
			(stroke
				(width 0.1)
				(type default)
			)
			(layer "B.Fab")
		)
		(fp_line
			(start 0.67945 -0.305054)
			(end 0.12065 -0.305054)
			(stroke
				(width 0.1)
				(type default)
			)
			(layer "B.Fab")
		)
		(pad "1" smd circle
			(at 0.40005 0 90)
			(size 0 0)
			(layers "B.Cu" "B.Mask" "B.Paste")
			(net "PVNN_TERM_CPU1")
		)
		(pad "2" smd circle
			(at -0.40005 0 90)
			(size 0 0)
			(layers "B.Cu" "B.Mask" "B.Paste")
			(net "FM_S3M_CPU1_LVC1_GPIO_2")
		)
	)
)
